FILE_TYPE = CONNECTIVITY;
{Allegro Design Entry HDL 17.4-2019 S026 (4007227) 1/17/2022}
"PAGE_NUMBER" = 152;
0"NC";
END.
